(kicad_pcb
	(version 20260206)
	(generator "pcbnew")
	(generator_version "10.0")
	(general
		(thickness 1.6)
		(legacy_teardrops no)
	)
	(paper "A4")
	(title_block
		(title "12092022_DA0F0TFB6D0_F0T_FAN_BOARD_MP5048_D_brd_v02_OCP.brd")
		(comment 1 "Grand Teton / footprints 297-301 of 924")
	)
	(layers
		(0 "F.Cu" signal "TOP")
		(4 "In1.Cu" signal "GND")
		(6 "In2.Cu" signal "IN1")
		(8 "In3.Cu" signal "IN2")
		(10 "In4.Cu" signal "GND1")
		(2 "B.Cu" signal "BOTTOM")
		(9 "F.Adhes" user "F.Adhesive")
		(11 "B.Adhes" user "B.Adhesive")
		(13 "F.Paste" user "Package Geometry/Pastemask Top")
		(15 "B.Paste" user "Package Geometry/Pastemask Bottom")
		(5 "F.SilkS" user "Ref Des/Silkscreen Top")
		(7 "B.SilkS" user "Ref Des/Silkscreen Bottom")
		(1 "F.Mask" user "Board Geometry/Soldermask Top")
		(3 "B.Mask" user "Board Geometry/Soldermask Bottom")
		(17 "Dwgs.User" user "User.Drawings")
		(19 "Cmts.User" user "User.Comments")
		(21 "Eco1.User" user "User.Eco1")
		(23 "Eco2.User" user "User.Eco2")
		(25 "Edge.Cuts" user "Board Geometry/Outline")
		(27 "Margin" user)
		(31 "F.CrtYd" user "Package Geometry/Place Bound Top")
		(29 "B.CrtYd" user "Package Geometry/Place Bound Bottom")
		(35 "F.Fab" user "Ref Des/Assembly Top")
		(33 "B.Fab" user "Ref Des/Assembly Bottom")
	)
	(footprint ""
		(layer "F.Cu")
		(at 18.161 -32.004 90)
		(property "Reference" "R5311"
			(at 0 0 90)
			(layer "F.SilkS")
			(hide yes)
			(effects
				(font
					(size 1.27 1.27)
				)
			)
		)
		(property "Value" ""
			(at 0 0 90)
			(layer "F.Fab")
			(effects
				(font
					(size 1.27 1.27)
				)
			)
		)
		(duplicate_pad_numbers_are_jumpers no)
		(fp_line
			(start 0.7874 -0.4064)
			(end 0.7874 0.4064)
			(stroke
				(width 0.1524)
				(type default)
			)
			(layer "F.SilkS")
		)
		(fp_line
			(start -0.7874 -0.4064)
			(end 0.7874 -0.4064)
			(stroke
				(width 0.1524)
				(type default)
			)
			(layer "F.SilkS")
		)
		(fp_line
			(start 0.7874 0.4064)
			(end -0.7874 0.4064)
			(stroke
				(width 0.1524)
				(type default)
			)
			(layer "F.SilkS")
		)
		(fp_line
			(start -0.7874 0.4064)
			(end -0.7874 -0.4064)
			(stroke
				(width 0.1524)
				(type default)
			)
			(layer "F.SilkS")
		)
		(fp_line
			(start -0.12065 -0.305054)
			(end -0.12065 -0.2794)
			(stroke
				(width 0.1)
				(type default)
			)
			(layer "F.Fab")
		)
		(fp_line
			(start -0.67945 -0.305054)
			(end -0.12065 -0.305054)
			(stroke
				(width 0.1)
				(type default)
			)
			(layer "F.Fab")
		)
		(fp_line
			(start 0.67945 -0.3048)
			(end 0.67945 0.3048)
			(stroke
				(width 0.1)
				(type default)
			)
			(layer "F.Fab")
		)
		(fp_line
			(start 0.12065 -0.3048)
			(end 0.67945 -0.3048)
			(stroke
				(width 0.1)
				(type default)
			)
			(layer "F.Fab")
		)
		(fp_line
			(start 0.12065 -0.2794)
			(end 0.12065 -0.3048)
			(stroke
				(width 0.1)
				(type default)
			)
			(layer "F.Fab")
		)
		(fp_line
			(start -0.12065 -0.2794)
			(end 0.12065 -0.2794)
			(stroke
				(width 0.1)
				(type default)
			)
			(layer "F.Fab")
		)
		(fp_line
			(start 0.120396 0.2794)
			(end -0.12065 0.2794)
			(stroke
				(width 0.1)
				(type default)
			)
			(layer "F.Fab")
		)
		(fp_line
			(start -0.12065 0.2794)
			(end -0.12065 0.3048)
			(stroke
				(width 0.1)
				(type default)
			)
			(layer "F.Fab")
		)
		(fp_line
			(start 0.67945 0.3048)
			(end 0.120396 0.3048)
			(stroke
				(width 0.1)
				(type default)
			)
			(layer "F.Fab")
		)
		(fp_line
			(start 0.120396 0.3048)
			(end 0.120396 0.2794)
			(stroke
				(width 0.1)
				(type default)
			)
			(layer "F.Fab")
		)
		(fp_line
			(start -0.12065 0.3048)
			(end -0.67945 0.3048)
			(stroke
				(width 0.1)
				(type default)
			)
			(layer "F.Fab")
		)
		(fp_line
			(start -0.67945 0.3048)
			(end -0.67945 -0.305054)
			(stroke
				(width 0.1)
				(type default)
			)
			(layer "F.Fab")
		)
		(pad "1" smd rect
			(at -0.40005 0 270)
			(size 0.4572 0.508)
			(layers "F.Cu" "F.Mask" "F.Paste")
			(net "FAN_4_TACH_OL_R")
		)
		(pad "2" smd rect
			(at 0.40005 0 270)
			(size 0.4572 0.508)
			(layers "F.Cu" "F.Mask" "F.Paste")
			(net "FAN_4_TACH_OL")
		)
	)
	(footprint ""
		(layer "F.Cu")
		(at 40.127428 -68.256912)
		(property "Reference" "R506"
			(at 0 0 0)
			(layer "F.SilkS")
			(hide yes)
			(effects
				(font
					(size 1.27 1.27)
				)
			)
		)
		(property "Value" ""
			(at 0 0 0)
			(layer "F.Fab")
			(effects
				(font
					(size 1.27 1.27)
				)
			)
		)
		(duplicate_pad_numbers_are_jumpers no)
		(fp_line
			(start -0.7874 -0.4064)
			(end 0.7874 -0.4064)
			(stroke
				(width 0.1524)
				(type default)
			)
			(layer "F.SilkS")
		)
		(fp_line
			(start -0.7874 0.4064)
			(end -0.7874 -0.4064)
			(stroke
				(width 0.1524)
				(type default)
			)
			(layer "F.SilkS")
		)
		(fp_line
			(start 0.7874 -0.4064)
			(end 0.7874 0.4064)
			(stroke
				(width 0.1524)
				(type default)
			)
			(layer "F.SilkS")
		)
		(fp_line
			(start 0.7874 0.4064)
			(end -0.7874 0.4064)
			(stroke
				(width 0.1524)
				(type default)
			)
			(layer "F.SilkS")
		)
		(fp_line
			(start -0.67945 -0.305054)
			(end -0.12065 -0.305054)
			(stroke
				(width 0.1)
				(type default)
			)
			(layer "F.Fab")
		)
		(fp_line
			(start -0.67945 0.3048)
			(end -0.67945 -0.305054)
			(stroke
				(width 0.1)
				(type default)
			)
			(layer "F.Fab")
		)
		(fp_line
			(start -0.12065 -0.305054)
			(end -0.12065 -0.2794)
			(stroke
				(width 0.1)
				(type default)
			)
			(layer "F.Fab")
		)
		(fp_line
			(start -0.12065 -0.2794)
			(end 0.12065 -0.2794)
			(stroke
				(width 0.1)
				(type default)
			)
			(layer "F.Fab")
		)
		(fp_line
			(start -0.12065 0.2794)
			(end -0.12065 0.3048)
			(stroke
				(width 0.1)
				(type default)
			)
			(layer "F.Fab")
		)
		(fp_line
			(start -0.12065 0.3048)
			(end -0.67945 0.3048)
			(stroke
				(width 0.1)
				(type default)
			)
			(layer "F.Fab")
		)
		(fp_line
			(start 0.120396 0.2794)
			(end -0.12065 0.2794)
			(stroke
				(width 0.1)
				(type default)
			)
			(layer "F.Fab")
		)
		(fp_line
			(start 0.120396 0.3048)
			(end 0.120396 0.2794)
			(stroke
				(width 0.1)
				(type default)
			)
			(layer "F.Fab")
		)
		(fp_line
			(start 0.12065 -0.3048)
			(end 0.67945 -0.3048)
			(stroke
				(width 0.1)
				(type default)
			)
			(layer "F.Fab")
		)
		(fp_line
			(start 0.12065 -0.2794)
			(end 0.12065 -0.3048)
			(stroke
				(width 0.1)
				(type default)
			)
			(layer "F.Fab")
		)
		(fp_line
			(start 0.67945 -0.3048)
			(end 0.67945 0.3048)
			(stroke
				(width 0.1)
				(type default)
			)
			(layer "F.Fab")
		)
		(fp_line
			(start 0.67945 0.3048)
			(end 0.120396 0.3048)
			(stroke
				(width 0.1)
				(type default)
			)
			(layer "F.Fab")
		)
		(pad "1" smd circle
			(at -0.40005 0)
			(size 0 0)
			(layers "F.Cu" "F.Mask" "F.Paste")
			(net "FAN_3_ON")
		)
		(pad "2" smd circle
			(at 0.40005 0)
			(size 0 0)
			(layers "F.Cu" "F.Mask" "F.Paste")
			(net "P52V_FAN_3_EN")
		)
	)
	(footprint ""
		(layer "F.Cu")
		(at 20.828 -174.752)
		(property "Reference" "R5675"
			(at 0 0 0)
			(layer "F.SilkS")
			(hide yes)
			(effects
				(font
					(size 1.27 1.27)
				)
			)
		)
		(property "Value" ""
			(at 0 0 0)
			(layer "F.Fab")
			(effects
				(font
					(size 1.27 1.27)
				)
			)
		)
		(duplicate_pad_numbers_are_jumpers no)
		(fp_line
			(start -0.7874 -0.4064)
			(end 0.7874 -0.4064)
			(stroke
				(width 0.1524)
				(type default)
			)
			(layer "F.SilkS")
		)
		(fp_line
			(start -0.7874 0.4064)
			(end -0.7874 -0.4064)
			(stroke
				(width 0.1524)
				(type default)
			)
			(layer "F.SilkS")
		)
		(fp_line
			(start 0.7874 -0.4064)
			(end 0.7874 0.4064)
			(stroke
				(width 0.1524)
				(type default)
			)
			(layer "F.SilkS")
		)
		(fp_line
			(start 0.7874 0.4064)
			(end -0.7874 0.4064)
			(stroke
				(width 0.1524)
				(type default)
			)
			(layer "F.SilkS")
		)
		(fp_line
			(start -0.67945 -0.305054)
			(end -0.12065 -0.305054)
			(stroke
				(width 0.1)
				(type default)
			)
			(layer "F.Fab")
		)
		(fp_line
			(start -0.67945 0.3048)
			(end -0.67945 -0.305054)
			(stroke
				(width 0.1)
				(type default)
			)
			(layer "F.Fab")
		)
		(fp_line
			(start -0.12065 -0.305054)
			(end -0.12065 -0.2794)
			(stroke
				(width 0.1)
				(type default)
			)
			(layer "F.Fab")
		)
		(fp_line
			(start -0.12065 -0.2794)
			(end 0.12065 -0.2794)
			(stroke
				(width 0.1)
				(type default)
			)
			(layer "F.Fab")
		)
		(fp_line
			(start -0.12065 0.2794)
			(end -0.12065 0.3048)
			(stroke
				(width 0.1)
				(type default)
			)
			(layer "F.Fab")
		)
		(fp_line
			(start -0.12065 0.3048)
			(end -0.67945 0.3048)
			(stroke
				(width 0.1)
				(type default)
			)
			(layer "F.Fab")
		)
		(fp_line
			(start 0.120396 0.2794)
			(end -0.12065 0.2794)
			(stroke
				(width 0.1)
				(type default)
			)
			(layer "F.Fab")
		)
		(fp_line
			(start 0.120396 0.3048)
			(end 0.120396 0.2794)
			(stroke
				(width 0.1)
				(type default)
			)
			(layer "F.Fab")
		)
		(fp_line
			(start 0.12065 -0.3048)
			(end 0.67945 -0.3048)
			(stroke
				(width 0.1)
				(type default)
			)
			(layer "F.Fab")
		)
		(fp_line
			(start 0.12065 -0.2794)
			(end 0.12065 -0.3048)
			(stroke
				(width 0.1)
				(type default)
			)
			(layer "F.Fab")
		)
		(fp_line
			(start 0.67945 -0.3048)
			(end 0.67945 0.3048)
			(stroke
				(width 0.1)
				(type default)
			)
			(layer "F.Fab")
		)
		(fp_line
			(start 0.67945 0.3048)
			(end 0.120396 0.3048)
			(stroke
				(width 0.1)
				(type default)
			)
			(layer "F.Fab")
		)
		(pad "1" smd circle
			(at -0.40005 0)
			(size 0 0)
			(layers "F.Cu" "F.Mask" "F.Paste")
			(net "FM_BOARD_SKU_ID2")
		)
		(pad "2" smd circle
			(at 0.40005 0)
			(size 0 0)
			(layers "F.Cu" "F.Mask" "F.Paste")
			(net "GND")
		)
	)
	(footprint ""
		(layer "F.Cu")
		(at 24.765 -152.019 90)
		(property "Reference" "U321"
			(at -2.032 -4.67233 90)
			(unlocked yes)
			(layer "F.SilkS")
			(effects
				(font
					(size 0.7874 0.5842)
					(thickness 0.1524)
				)
				(justify left)
			)
		)
		(property "Value" ""
			(at 0 0 90)
			(layer "F.Fab")
			(effects
				(font
					(size 1.27 1.27)
				)
			)
		)
		(duplicate_pad_numbers_are_jumpers no)
		(fp_line
			(start 2.0066 -3.9624)
			(end 2.0066 3.9624)
			(stroke
				(width 0.1524)
				(type default)
			)
			(layer "F.SilkS")
		)
		(fp_line
			(start 0.5842 -3.9624)
			(end 2.0066 -3.9624)
			(stroke
				(width 0.1524)
				(type default)
			)
			(layer "F.SilkS")
		)
		(fp_line
			(start -0.5842 -3.9624)
			(end 0 -3.3782)
			(stroke
				(width 0.1524)
				(type default)
			)
			(layer "F.SilkS")
		)
		(fp_line
			(start -2.0066 -3.9624)
			(end -0.5842 -3.9624)
			(stroke
				(width 0.1524)
				(type default)
			)
			(layer "F.SilkS")
		)
		(fp_line
			(start 0 -3.3782)
			(end 0.5842 -3.9624)
			(stroke
				(width 0.1524)
				(type default)
			)
			(layer "F.SilkS")
		)
		(fp_line
			(start 2.0066 3.9624)
			(end -2.0066 3.9624)
			(stroke
				(width 0.1524)
				(type default)
			)
			(layer "F.SilkS")
		)
		(fp_line
			(start -2.0066 3.9624)
			(end -2.0066 -3.9624)
			(stroke
				(width 0.1524)
				(type default)
			)
			(layer "F.SilkS")
		)
		(fp_poly
			(pts
				(xy -3.8862 -3.570986) (xy -4.6482 -3.189986) (xy -4.6482 -3.951986)
			)
			(stroke
				(width 0)
				(type default)
			)
			(fill yes)
			(layer "F.SilkS")
		)
		(fp_line
			(start 2.2479 -3.974846)
			(end -2.2479 -3.974846)
			(stroke
				(width 0.1)
				(type default)
			)
			(layer "F.Fab")
		)
		(fp_line
			(start -2.2479 -3.974846)
			(end -2.2479 -3.80365)
			(stroke
				(width 0.1)
				(type default)
			)
			(layer "F.Fab")
		)
		(fp_line
			(start 3.7211 -3.80365)
			(end 2.2479 -3.80365)
			(stroke
				(width 0.1)
				(type default)
			)
			(layer "F.Fab")
		)
		(fp_line
			(start 2.2479 -3.80365)
			(end 2.2479 -3.974846)
			(stroke
				(width 0.1)
				(type default)
			)
			(layer "F.Fab")
		)
		(fp_line
			(start -2.2479 -3.80365)
			(end -3.724402 -3.80365)
			(stroke
				(width 0.1)
				(type default)
			)
			(layer "F.Fab")
		)
		(fp_line
			(start -3.724402 -3.80365)
			(end -3.724402 3.80365)
			(stroke
				(width 0.1)
				(type default)
			)
			(layer "F.Fab")
		)
		(fp_line
			(start -3.7211 -3.34645)
			(end -3.7211 -3.80365)
			(stroke
				(width 0.1)
				(type default)
			)
			(layer "F.Fab")
		)
		(fp_line
			(start 3.7211 3.80365)
			(end 3.7211 -3.80365)
			(stroke
				(width 0.1)
				(type default)
			)
			(layer "F.Fab")
		)
		(fp_line
			(start 2.2479 3.80365)
			(end 3.7211 3.80365)
			(stroke
				(width 0.1)
				(type default)
			)
			(layer "F.Fab")
		)
		(fp_line
			(start -2.2479 3.80365)
			(end -2.2479 3.9624)
			(stroke
				(width 0.1)
				(type default)
			)
			(layer "F.Fab")
		)
		(fp_line
			(start -3.724402 3.80365)
			(end -2.2479 3.80365)
			(stroke
				(width 0.1)
				(type default)
			)
			(layer "F.Fab")
		)
		(fp_line
			(start 2.2479 3.9624)
			(end 2.2479 3.80365)
			(stroke
				(width 0.1)
				(type default)
			)
			(layer "F.Fab")
		)
		(fp_line
			(start -2.2479 3.9624)
			(end 2.2479 3.9624)
			(stroke
				(width 0.1)
				(type default)
			)
			(layer "F.Fab")
		)
		(fp_poly
			(pts
				(xy -3.8862 -3.570986) (xy -4.6482 -3.189986) (xy -4.6482 -3.951986)
			)
			(stroke
				(width 0)
				(type default)
			)
			(fill yes)
			(layer "F.Fab")
		)
		(pad "1" smd rect
			(at -2.921 -3.57505)
			(size 0.3556 1.4986)
			(layers "F.Cu" "F.Mask" "F.Paste")
			(net "PD_TCA9548_SML1_U321_A0")
		)
		(pad "2" smd rect
			(at -2.921 -2.925064)
			(size 0.3556 1.4986)
			(layers "F.Cu" "F.Mask" "F.Paste")
			(net "PD_TCA9548_SML1_U321_A1")
		)
		(pad "3" smd rect
			(at -2.921 -2.275078)
			(size 0.3556 1.4986)
			(layers "F.Cu" "F.Mask" "F.Paste")
			(net "RST_SMB_PDB_R_N")
		)
		(pad "4" smd rect
			(at -2.921 -1.625092)
			(size 0.3556 1.4986)
			(layers "F.Cu" "F.Mask" "F.Paste")
			(net "SMB_FAN0_R_SDA")
		)
		(pad "5" smd rect
			(at -2.921 -0.975106)
			(size 0.3556 1.4986)
			(layers "F.Cu" "F.Mask" "F.Paste")
			(net "SMB_FAN0_R_SCL")
		)
		(pad "6" smd rect
			(at -2.921 -0.32512)
			(size 0.3556 1.4986)
			(layers "F.Cu" "F.Mask" "F.Paste")
			(net "SMB_FAN1_R_SDA")
		)
		(pad "7" smd rect
			(at -2.921 0.32512)
			(size 0.3556 1.4986)
			(layers "F.Cu" "F.Mask" "F.Paste")
			(net "SMB_FAN1_R_SCL")
		)
		(pad "8" smd rect
			(at -2.921 0.975106)
			(size 0.3556 1.4986)
			(layers "F.Cu" "F.Mask" "F.Paste")
			(net "SMB_FAN2_R_SDA")
		)
		(pad "9" smd rect
			(at -2.921 1.625092)
			(size 0.3556 1.4986)
			(layers "F.Cu" "F.Mask" "F.Paste")
			(net "SMB_FAN2_R_SCL")
		)
		(pad "10" smd rect
			(at -2.921 2.275078)
			(size 0.3556 1.4986)
			(layers "F.Cu" "F.Mask" "F.Paste")
			(net "SMB_FAN3_R_SDA")
		)
		(pad "11" smd rect
			(at -2.921 2.925064)
			(size 0.3556 1.4986)
			(layers "F.Cu" "F.Mask" "F.Paste")
			(net "SMB_FAN3_R_SCL")
		)
		(pad "12" smd rect
			(at -2.921 3.57505)
			(size 0.3556 1.4986)
			(layers "F.Cu" "F.Mask" "F.Paste")
			(net "GND")
		)
		(pad "13" smd rect
			(at 2.921 3.57505)
			(size 0.3556 1.4986)
			(layers "F.Cu" "F.Mask" "F.Paste")
			(net "SMB_FAN4_R_SDA")
		)
		(pad "14" smd rect
			(at 2.921 2.925064)
			(size 0.3556 1.4986)
			(layers "F.Cu" "F.Mask" "F.Paste")
			(net "SMB_FAN4_R_SCL")
		)
		(pad "15" smd rect
			(at 2.921 2.275078)
			(size 0.3556 1.4986)
			(layers "F.Cu" "F.Mask" "F.Paste")
			(net "SMB_FAN5_R_SDA")
		)
		(pad "16" smd rect
			(at 2.921 1.625092)
			(size 0.3556 1.4986)
			(layers "F.Cu" "F.Mask" "F.Paste")
			(net "SMB_FAN5_R_SCL")
		)
		(pad "17" smd rect
			(at 2.921 0.975106)
			(size 0.3556 1.4986)
			(layers "F.Cu" "F.Mask" "F.Paste")
			(net "SMB_FAN6_R_SDA")
		)
		(pad "18" smd rect
			(at 2.921 0.32512)
			(size 0.3556 1.4986)
			(layers "F.Cu" "F.Mask" "F.Paste")
			(net "SMB_FAN6_R_SCL")
		)
		(pad "19" smd rect
			(at 2.921 -0.32512)
			(size 0.3556 1.4986)
			(layers "F.Cu" "F.Mask" "F.Paste")
			(net "SMB_FAN7_R_SDA")
		)
		(pad "20" smd rect
			(at 2.921 -0.975106)
			(size 0.3556 1.4986)
			(layers "F.Cu" "F.Mask" "F.Paste")
			(net "SMB_FAN7_R_SCL")
		)
		(pad "21" smd rect
			(at 2.921 -1.625092)
			(size 0.3556 1.4986)
			(layers "F.Cu" "F.Mask" "F.Paste")
			(net "PD_TCA9548_SML1_U321_A2")
		)
		(pad "22" smd rect
			(at 2.921 -2.275078)
			(size 0.3556 1.4986)
			(layers "F.Cu" "F.Mask" "F.Paste")
			(net "SMB_PDBV_FAN_R_U321_SCL")
		)
		(pad "23" smd rect
			(at 2.921 -2.925064)
			(size 0.3556 1.4986)
			(layers "F.Cu" "F.Mask" "F.Paste")
			(net "SMB_PDBV_FAN_R_U321_SDA")
		)
		(pad "24" smd rect
			(at 2.921 -3.57505)
			(size 0.3556 1.4986)
			(layers "F.Cu" "F.Mask" "F.Paste")
			(net "P3V3_AUX")
		)
	)
	(footprint ""
		(layer "F.Cu")
		(at 44.831 -135.509 -90)
		(property "Reference" "C2094"
			(at 0 0 270)
			(layer "F.SilkS")
			(hide yes)
			(effects
				(font
					(size 1.27 1.27)
				)
			)
		)
		(property "Value" ""
			(at 0 0 270)
			(layer "F.Fab")
			(effects
				(font
					(size 1.27 1.27)
				)
			)
		)
		(duplicate_pad_numbers_are_jumpers no)
		(fp_line
			(start -0.7874 0.4064)
			(end -0.7874 -0.4064)
			(stroke
				(width 0.1524)
				(type default)
			)
			(layer "F.SilkS")
		)
		(fp_line
			(start 0.7874 0.4064)
			(end -0.7874 0.4064)
			(stroke
				(width 0.1524)
				(type default)
			)
			(layer "F.SilkS")
		)
		(fp_line
			(start -0.7874 -0.4064)
			(end 0.7874 -0.4064)
			(stroke
				(width 0.1524)
				(type default)
			)
			(layer "F.SilkS")
		)
		(fp_line
			(start 0.7874 -0.4064)
			(end 0.7874 0.4064)
			(stroke
				(width 0.1524)
				(type default)
			)
			(layer "F.SilkS")
		)
		(fp_line
			(start -0.67945 0.3048)
			(end -0.67945 -0.305054)
			(stroke
				(width 0.1)
				(type default)
			)
			(layer "F.Fab")
		)
		(fp_line
			(start -0.12065 0.3048)
			(end -0.67945 0.3048)
			(stroke
				(width 0.1)
				(type default)
			)
			(layer "F.Fab")
		)
		(fp_line
			(start 0.120396 0.3048)
			(end 0.120396 0.2794)
			(stroke
				(width 0.1)
				(type default)
			)
			(layer "F.Fab")
		)
		(fp_line
			(start 0.67945 0.3048)
			(end 0.120396 0.3048)
			(stroke
				(width 0.1)
				(type default)
			)
			(layer "F.Fab")
		)
		(fp_line
			(start -0.12065 0.2794)
			(end -0.12065 0.3048)
			(stroke
				(width 0.1)
				(type default)
			)
			(layer "F.Fab")
		)
		(fp_line
			(start 0.120396 0.2794)
			(end -0.12065 0.2794)
			(stroke
				(width 0.1)
				(type default)
			)
			(layer "F.Fab")
		)
		(fp_line
			(start -0.12065 -0.2794)
			(end 0.12065 -0.2794)
			(stroke
				(width 0.1)
				(type default)
			)
			(layer "F.Fab")
		)
		(fp_line
			(start 0.12065 -0.2794)
			(end 0.12065 -0.3048)
			(stroke
				(width 0.1)
				(type default)
			)
			(layer "F.Fab")
		)
		(fp_line
			(start 0.12065 -0.3048)
			(end 0.67945 -0.3048)
			(stroke
				(width 0.1)
				(type default)
			)
			(layer "F.Fab")
		)
		(fp_line
			(start 0.67945 -0.3048)
			(end 0.67945 0.3048)
			(stroke
				(width 0.1)
				(type default)
			)
			(layer "F.Fab")
		)
		(fp_line
			(start -0.67945 -0.305054)
			(end -0.12065 -0.305054)
			(stroke
				(width 0.1)
				(type default)
			)
			(layer "F.Fab")
		)
		(fp_line
			(start -0.12065 -0.305054)
			(end -0.12065 -0.2794)
			(stroke
				(width 0.1)
				(type default)
			)
			(layer "F.Fab")
		)
		(pad "1" smd circle
			(at -0.40005 0 270)
			(size 0 0)
			(layers "F.Cu" "F.Mask" "F.Paste")
			(net "GND")
		)
		(pad "2" smd circle
			(at 0.40005 0 270)
			(size 0 0)
			(layers "F.Cu" "F.Mask" "F.Paste")
			(net "P3V3_AUX")
		)
	)
)
